FILE_TYPE = MACRO_DRAWING;
SET COLOR_WIRE YELLOW;
SET COLOR_PROP ORANGE;
SET COLOR_DOT WHITE;
SET COLOR_ARC YELLOW;
SET COLOR_BODY GREEN;
SET COLOR_NOTE PURPLE;
SET PROP_DISPLAY VALUE;
SET PAGE_NUMBER P218;
FORCEADD OFFPAGE..1
(-1100 1475);
FORCEPROP 2 LAST $XR0 229 
J 0
(-1352 1475);
DISPLAY 0.638298 (-1352 1475);
PAINT MONO (-1352 1475);
FORCEPROP 1 LAST COMMENT_BODY TRUE
J 0
(-975 1375);
DISPLAY 0.872340 (-975 1375);
PAINT GREEN (-975 1375);
DISPLAY INVISIBLE (-975 1375);
FORCEPROP 1 LAST OFFPAGE TRUE
J 0
(-775 1350);
DISPLAY 0.872340 (-775 1350);
PAINT GREEN (-775 1350);
DISPLAY INVISIBLE (-775 1350);
FORCEPROP 2 LAST CDS_LIB standard
J 0
(-1100 1475);
PAINT MONO (-1100 1475);
DISPLAY INVISIBLE (-1100 1475);
FORCEPROP 2 LAST PATH I1
J 0
(-1350 1525);
DISPLAY 1.021277 (-1350 1525);
DISPLAY INVISIBLE (-1350 1525);
FORCEADD OFFPAGE..1
(-1100 2025);
FORCEPROP 2 LAST $XR0 230 
J 0
(-1352 2025);
DISPLAY 0.638298 (-1352 2025);
PAINT MONO (-1352 2025);
FORCEPROP 1 LAST COMMENT_BODY TRUE
J 0
(-975 1925);
DISPLAY 0.872340 (-975 1925);
PAINT GREEN (-975 1925);
DISPLAY INVISIBLE (-975 1925);
FORCEPROP 1 LAST OFFPAGE TRUE
J 0
(-775 1900);
DISPLAY 0.872340 (-775 1900);
PAINT GREEN (-775 1900);
DISPLAY INVISIBLE (-775 1900);
FORCEPROP 2 LAST CDS_LIB standard
J 0
(-1100 2025);
PAINT MONO (-1100 2025);
DISPLAY INVISIBLE (-1100 2025);
FORCEPROP 2 LAST PATH I10
J 0
(-1350 2075);
DISPLAY 1.021277 (-1350 2075);
DISPLAY INVISIBLE (-1350 2075);
FORCEADD OFFPAGE..1
(-1100 2075);
FORCEPROP 2 LAST $XR0 241 
J 0
(-1352 2075);
DISPLAY 0.638298 (-1352 2075);
PAINT MONO (-1352 2075);
FORCEPROP 1 LAST COMMENT_BODY TRUE
J 0
(-975 1975);
DISPLAY 0.872340 (-975 1975);
PAINT GREEN (-975 1975);
DISPLAY INVISIBLE (-975 1975);
FORCEPROP 1 LAST OFFPAGE TRUE
J 0
(-775 1950);
DISPLAY 0.872340 (-775 1950);
PAINT GREEN (-775 1950);
DISPLAY INVISIBLE (-775 1950);
FORCEPROP 2 LAST CDS_LIB standard
J 0
(-1100 2075);
PAINT MONO (-1100 2075);
DISPLAY INVISIBLE (-1100 2075);
FORCEPROP 2 LAST PATH I11
J 0
(-1350 2125);
DISPLAY 1.021277 (-1350 2125);
DISPLAY INVISIBLE (-1350 2125);
FORCEADD QS3VH257QG8..1
R 2
(650 1750);
FORCEPROP 1 LAST PART_NUMBER AL000257W24
J 2
(800 2185);
DISPLAY 0.723404 (800 2185);
PAINT GREEN (800 2185);
DISPLAY INVISIBLE (800 2185);
FORCEPROP 2 LAST PACK_TYPE SMLF
J 2
(800 2275);
DISPLAY 1.021277 (800 2275);
FORCEPROP 2 LAST VALUE QS3VH257QG8
J 2
(800 2325);
DISPLAY 1.021277 (800 2325);
FORCEPROP 1 LAST MATERIAL IC
J 2
(800 2135);
DISPLAY 0.723404 (800 2135);
PAINT GREEN (800 2135);
FORCEPROP 1 LAST LOCATION U14
J 2
(800 2230);
DISPLAY 0.723404 (800 2230);
PAINT GREEN (800 2230);
FORCEPROP 0 LASTPIN (350 1425) $PN 15
J 2
(340 1435);
DISPLAY 0.680851 (340 1435);
PAINT MONO (340 1435);
FORCEPROP 0 LASTPIN (950 1425) $PN 8
J 0
(960 1435);
DISPLAY 0.680851 (960 1435);
PAINT MONO (960 1435);
FORCEPROP 0 LASTPIN (350 2025) $PN 2
J 2
(340 2035);
DISPLAY 0.680851 (340 2035);
PAINT MONO (340 2035);
FORCEPROP 0 LASTPIN (350 1875) $PN 5
J 2
(340 1885);
DISPLAY 0.680851 (340 1885);
PAINT MONO (340 1885);
FORCEPROP 0 LASTPIN (350 1725) $PN 11
J 2
(340 1735);
DISPLAY 0.680851 (340 1735);
PAINT MONO (340 1735);
FORCEPROP 0 LASTPIN (350 1575) $PN 14
J 2
(340 1585);
DISPLAY 0.680851 (340 1585);
PAINT MONO (340 1585);
FORCEPROP 0 LASTPIN (350 2075) $PN 3
J 2
(340 2085);
DISPLAY 0.680851 (340 2085);
PAINT MONO (340 2085);
FORCEPROP 0 LASTPIN (350 1925) $PN 6
J 2
(340 1935);
DISPLAY 0.680851 (340 1935);
PAINT MONO (340 1935);
FORCEPROP 0 LASTPIN (350 1775) $PN 10
J 2
(340 1785);
DISPLAY 0.680851 (340 1785);
PAINT MONO (340 1785);
FORCEPROP 0 LASTPIN (350 1625) $PN 13
J 2
(340 1635);
DISPLAY 0.680851 (340 1635);
PAINT MONO (340 1635);
FORCEPROP 0 LASTPIN (350 1475) $PN 1
J 2
(340 1485);
DISPLAY 0.680851 (340 1485);
PAINT MONO (340 1485);
FORCEPROP 0 LASTPIN (950 2075) $PN 16
J 0
(960 2085);
DISPLAY 0.680851 (960 2085);
PAINT MONO (960 2085);
FORCEPROP 0 LASTPIN (950 2025) $PN 4
J 0
(960 2035);
DISPLAY 0.680851 (960 2035);
PAINT MONO (960 2035);
FORCEPROP 0 LASTPIN (950 1875) $PN 7
J 0
(960 1885);
DISPLAY 0.680851 (960 1885);
PAINT MONO (960 1885);
FORCEPROP 0 LASTPIN (950 1725) $PN 9
J 0
(960 1735);
DISPLAY 0.680851 (960 1735);
PAINT MONO (960 1735);
FORCEPROP 0 LASTPIN (950 1575) $PN 12
J 0
(960 1585);
DISPLAY 0.680851 (960 1585);
PAINT MONO (960 1585);
FORCEPROP 1 LAST NEEDS_NO_SIZE TRUE
J 2
(650 1750);
DISPLAY 0.468085 (650 1750);
PAINT GREEN (650 1750);
DISPLAY INVISIBLE (650 1750);
FORCEPROP 1 LAST CDS_LMAN_SYM_OUTLINE -150,375,150,-375
J 2
(650 1750);
DISPLAY 0.468085 (650 1750);
PAINT GREEN (650 1750);
DISPLAY INVISIBLE (650 1750);
FORCEPROP 2 LAST CDS_LIB pure_quanta
J 0
(650 1750);
DISPLAY INVISIBLE (650 1750);
FORCEPROP 1 LAST PATH I12
J 2
(525 2130);
DISPLAY 0.723404 (525 2130);
PAINT GREEN (525 2130);
DISPLAY INVISIBLE (525 2130);
FORCEPROP 0 LAST $SEC 1
J 0
(800 2375);
DISPLAY 0.680851 (800 2375);
PAINT MONO (800 2375);
DISPLAY INVISIBLE (800 2375);
FORCEPROP 0 LAST CDS_SEC 1
J 0
(800 2375);
DISPLAY 1.021277 (800 2375);
DISPLAY INVISIBLE (800 2375);
FORCEADD OFFPAGE..3
R 2
(-1100 3625);
FORCEPROP 2 LAST $XR0 44 
J 0
(-1349 3625);
DISPLAY 0.638298 (-1349 3625);
PAINT MONO (-1349 3625);
FORCEPROP 1 LAST COMMENT_BODY TRUE
J 2
(-1050 3525);
DISPLAY 0.872340 (-1050 3525);
PAINT GREEN (-1050 3525);
DISPLAY INVISIBLE (-1050 3525);
FORCEPROP 1 LAST OFFPAGE TRUE
J 2
(-1425 3500);
DISPLAY 0.872340 (-1425 3500);
DISPLAY INVISIBLE (-1425 3500);
FORCEPROP 2 LAST CDS_LIB standard
J 0
(-1100 3625);
PAINT MONO (-1100 3625);
DISPLAY INVISIBLE (-1100 3625);
FORCEPROP 2 LAST PATH I13
J 0
(-1325 3675);
DISPLAY 1.021277 (-1325 3675);
DISPLAY INVISIBLE (-1325 3675);
FORCEADD OFFPAGE..1
(-1100 3675);
FORCEPROP 2 LAST $XR0 44 
J 0
(-1321 3675);
DISPLAY 0.638298 (-1321 3675);
PAINT MONO (-1321 3675);
FORCEPROP 1 LAST COMMENT_BODY TRUE
J 0
(-975 3575);
DISPLAY 0.872340 (-975 3575);
PAINT GREEN (-975 3575);
DISPLAY INVISIBLE (-975 3575);
FORCEPROP 1 LAST OFFPAGE TRUE
J 0
(-775 3550);
DISPLAY 0.872340 (-775 3550);
PAINT GREEN (-775 3550);
DISPLAY INVISIBLE (-775 3550);
FORCEPROP 2 LAST CDS_LIB standard
J 0
(-1100 3675);
PAINT MONO (-1100 3675);
DISPLAY INVISIBLE (-1100 3675);
FORCEPROP 2 LAST PATH I14
J 0
(-1300 3725);
DISPLAY 1.021277 (-1300 3725);
DISPLAY INVISIBLE (-1300 3725);
FORCEADD OFFPAGE..1
(-1100 3975);
FORCEPROP 2 LAST $XR0 44 
J 0
(-1321 3975);
DISPLAY 0.638298 (-1321 3975);
PAINT MONO (-1321 3975);
FORCEPROP 1 LAST COMMENT_BODY TRUE
J 0
(-975 3875);
DISPLAY 0.872340 (-975 3875);
PAINT GREEN (-975 3875);
DISPLAY INVISIBLE (-975 3875);
FORCEPROP 1 LAST OFFPAGE TRUE
J 0
(-775 3850);
DISPLAY 0.872340 (-775 3850);
PAINT GREEN (-775 3850);
DISPLAY INVISIBLE (-775 3850);
FORCEPROP 2 LAST CDS_LIB standard
J 0
(-1100 3975);
PAINT MONO (-1100 3975);
DISPLAY INVISIBLE (-1100 3975);
FORCEPROP 2 LAST PATH I15
J 0
(-1300 4025);
DISPLAY 1.021277 (-1300 4025);
DISPLAY INVISIBLE (-1300 4025);
FORCEADD OFFPAGE..3
R 2
(-1100 3925);
FORCEPROP 2 LAST $XR0 44 
J 0
(-1349 3925);
DISPLAY 0.638298 (-1349 3925);
PAINT MONO (-1349 3925);
FORCEPROP 1 LAST COMMENT_BODY TRUE
J 2
(-1050 3825);
DISPLAY 0.872340 (-1050 3825);
PAINT GREEN (-1050 3825);
DISPLAY INVISIBLE (-1050 3825);
FORCEPROP 1 LAST OFFPAGE TRUE
J 2
(-1425 3800);
DISPLAY 0.872340 (-1425 3800);
DISPLAY INVISIBLE (-1425 3800);
FORCEPROP 2 LAST CDS_LIB standard
J 0
(-1100 3925);
PAINT MONO (-1100 3925);
DISPLAY INVISIBLE (-1100 3925);
FORCEPROP 2 LAST PATH I16
J 0
(-1325 3975);
DISPLAY 1.021277 (-1325 3975);
DISPLAY INVISIBLE (-1325 3975);
FORCEADD Q_RES..2
(-25 4300);
FORCEPROP 1 LAST PART_NUMBER CS14992FB06
J 0
(15 4125);
DISPLAY 0.638298 (15 4125);
DISPLAY INVISIBLE (15 4125);
FORCEPROP 1 LAST PACK_TYPE 0402LF
J 0
(15 4175);
DISPLAY 0.638298 (15 4175);
FORCEPROP 1 LAST WATTAGE 1/16W
J 0
(15 4275);
DISPLAY 0.638298 (15 4275);
FORCEPROP 1 LAST MATERIAL CHIP
J 0
(15 4225);
DISPLAY 0.638298 (15 4225);
FORCEPROP 1 LAST TOLERANCE 1%
J 0
(20 4325);
DISPLAY 0.638298 (20 4325);
FORCEPROP 1 LAST VALUE 499
J 0
(20 4375);
DISPLAY 0.638298 (20 4375);
FORCEPROP 1 LAST $LOCATION R662
J 0
(20 4425);
DISPLAY 0.978723 (20 4425);
FORCEPROP 1 LASTPIN (-25 4400) $PN 1
J 0
(-20 4362);
DISPLAY 0.787234 (-20 4362);
FORCEPROP 1 LASTPIN (-25 4200) $PN 2
J 0
(-20 4210);
DISPLAY 0.787234 (-20 4210);
FORCEPROP 2 LAST CDS_LIB pure_quanta
J 0
(-25 4300);
PAINT MONO (-25 4300);
DISPLAY INVISIBLE (-25 4300);
FORCEPROP 1 LAST PATH I17
J 0
(25 4475);
DISPLAY 0.978723 (25 4475);
PAINT WHITE (25 4475);
DISPLAY INVISIBLE (25 4475);
FORCEPROP 2 LAST CDS_LOCATION R662
J 0
(25 4525);
DISPLAY 1.021277 (25 4525);
DISPLAY INVISIBLE (25 4525);
FORCEPROP 2 LAST $SEC 1
J 0
(25 4525);
DISPLAY 0.680851 (25 4525);
PAINT MONO (25 4525);
DISPLAY INVISIBLE (25 4525);
FORCEPROP 2 LAST CDS_SEC 1
J 0
(25 4525);
DISPLAY 1.021277 (25 4525);
DISPLAY INVISIBLE (25 4525);
FORCEADD Q_RES..2
(225 4300);
FORCEPROP 1 LAST PART_NUMBER CS14992FB06
J 0
(265 4125);
DISPLAY 0.638298 (265 4125);
DISPLAY INVISIBLE (265 4125);
FORCEPROP 1 LAST TOLERANCE 1%
J 0
(270 4325);
DISPLAY 0.638298 (270 4325);
FORCEPROP 1 LAST MATERIAL CHIP
J 0
(265 4225);
DISPLAY 0.638298 (265 4225);
FORCEPROP 1 LAST WATTAGE 1/16W
J 0
(265 4275);
DISPLAY 0.638298 (265 4275);
FORCEPROP 1 LAST PACK_TYPE 0402LF
J 0
(265 4175);
DISPLAY 0.638298 (265 4175);
FORCEPROP 1 LAST VALUE 499
J 0
(270 4375);
DISPLAY 0.638298 (270 4375);
FORCEPROP 1 LAST $LOCATION R663
J 0
(270 4425);
DISPLAY 0.978723 (270 4425);
FORCEPROP 1 LASTPIN (225 4400) $PN 1
J 0
(230 4362);
DISPLAY 0.787234 (230 4362);
FORCEPROP 1 LASTPIN (225 4200) $PN 2
J 0
(230 4210);
DISPLAY 0.787234 (230 4210);
FORCEPROP 2 LAST CDS_LIB pure_quanta
J 0
(225 4300);
PAINT MONO (225 4300);
DISPLAY INVISIBLE (225 4300);
FORCEPROP 1 LAST PATH I18
J 0
(275 4475);
DISPLAY 0.978723 (275 4475);
PAINT WHITE (275 4475);
DISPLAY INVISIBLE (275 4475);
FORCEPROP 2 LAST CDS_LOCATION R663
J 0
(275 4525);
DISPLAY 1.021277 (275 4525);
DISPLAY INVISIBLE (275 4525);
FORCEPROP 2 LAST $SEC 1
J 0
(275 4525);
DISPLAY 0.680851 (275 4525);
PAINT MONO (275 4525);
DISPLAY INVISIBLE (275 4525);
FORCEPROP 2 LAST CDS_SEC 1
J 0
(275 4525);
DISPLAY 1.021277 (275 4525);
DISPLAY INVISIBLE (275 4525);
FORCEADD UNIVERSAL_POWER..1
(-25 4675);
FORCEPROP 3 LASTPIN (-25 4625) SIG_NAME PVNN_TERM_CPU1\g
J 0
(-15 4635);
DISPLAY 0.659574 (-15 4635);
PAINT MONO (-15 4635);
DISPLAY INVISIBLE (-15 4635);
FORCEPROP 1 LAST HDL_POWER PVNN_TERM_CPU1
J 1
(-25 4725);
DISPLAY 0.702128 (-25 4725);
PAINT GREEN (-25 4725);
FORCEPROP 2 LAST CDS_LIB logical_power
J 0
(-25 4675);
PAINT MONO (-25 4675);
DISPLAY INVISIBLE (-25 4675);
FORCEPROP 1 LAST PATH I19
J 0
(25 4700);
DISPLAY 0.872340 (25 4700);
PAINT AQUA (25 4700);
DISPLAY INVISIBLE (25 4700);
FORCEADD OFFPAGE..3
R 2
(-1100 1575);
FORCEPROP 2 LAST $XR0 230 
J 0
(-1380 1575);
DISPLAY 0.638298 (-1380 1575);
PAINT MONO (-1380 1575);
FORCEPROP 1 LAST COMMENT_BODY TRUE
J 2
(-1050 1475);
DISPLAY 0.872340 (-1050 1475);
PAINT GREEN (-1050 1475);
DISPLAY INVISIBLE (-1050 1475);
FORCEPROP 1 LAST OFFPAGE TRUE
J 2
(-1425 1450);
DISPLAY 0.872340 (-1425 1450);
DISPLAY INVISIBLE (-1425 1450);
FORCEPROP 2 LAST CDS_LIB standard
J 0
(-1100 1575);
PAINT MONO (-1100 1575);
DISPLAY INVISIBLE (-1100 1575);
FORCEPROP 2 LAST PATH I2
J 0
(-1375 1625);
DISPLAY 1.021277 (-1375 1625);
DISPLAY INVISIBLE (-1375 1625);
FORCEADD Q_RES..1
(625 775);
FORCEPROP 1 LAST PART_NUMBER CS00002JB13
J 0
(575 825);
DISPLAY 0.404255 (575 825);
DISPLAY INVISIBLE (575 825);
FORCEPROP 1 LAST WATTAGE 1/16W
J 2
(800 850);
DISPLAY 0.404255 (800 850);
FORCEPROP 1 LAST PACK_TYPE 0402LF
J 0
(575 850);
DISPLAY 0.404255 (575 850);
FORCEPROP 1 LAST TOLERANCE 5%
J 0
(800 775);
DISPLAY 0.510638 (800 775);
FORCEPROP 1 LAST VALUE 0
J 2
(775 775);
DISPLAY 0.510638 (775 775);
FORCEPROP 1 LAST MATERIAL EMPTY
J 0
(875 775);
DISPLAY 0.510638 (875 775);
PAINT RED (875 775);
FORCEPROP 1 LAST $LOCATION R668
J 0
(425 775);
DISPLAY 0.638298 (425 775);
FORCEPROP 1 LASTPIN (525 775) $PN 1
J 0
(537 787);
DISPLAY 0.787234 (537 787);
FORCEPROP 1 LASTPIN (725 775) $PN 2
J 0
(687 787);
DISPLAY 0.787234 (687 787);
FORCEPROP 2 LAST CDS_LIB pure_quanta
J 0
(625 775);
PAINT MONO (625 775);
DISPLAY INVISIBLE (625 775);
FORCEPROP 1 LAST PATH I20
J 0
(575 925);
DISPLAY 0.978723 (575 925);
PAINT WHITE (575 925);
DISPLAY INVISIBLE (575 925);
FORCEPROP 2 LAST CDS_LOCATION R668
J 0
(575 975);
DISPLAY 1.021277 (575 975);
DISPLAY INVISIBLE (575 975);
FORCEPROP 2 LAST $SEC 1
J 0
(575 975);
DISPLAY 0.680851 (575 975);
PAINT MONO (575 975);
DISPLAY INVISIBLE (575 975);
FORCEPROP 2 LAST CDS_SEC 1
J 0
(575 975);
DISPLAY 1.021277 (575 975);
DISPLAY INVISIBLE (575 975);
FORCEADD Q_RES..1
(625 900);
FORCEPROP 1 LAST PART_NUMBER CS00002JB13
J 0
(575 950);
DISPLAY 0.404255 (575 950);
DISPLAY INVISIBLE (575 950);
FORCEPROP 1 LAST MATERIAL EMPTY
J 0
(875 900);
DISPLAY 0.510638 (875 900);
PAINT RED (875 900);
FORCEPROP 1 LAST PACK_TYPE 0402LF
J 0
(575 975);
DISPLAY 0.404255 (575 975);
FORCEPROP 1 LAST WATTAGE 1/16W
J 2
(800 975);
DISPLAY 0.404255 (800 975);
FORCEPROP 1 LAST VALUE 0
J 2
(775 900);
DISPLAY 0.510638 (775 900);
FORCEPROP 1 LAST TOLERANCE 5%
J 0
(800 900);
DISPLAY 0.510638 (800 900);
FORCEPROP 1 LAST $LOCATION R667
J 0
(425 900);
DISPLAY 0.638298 (425 900);
FORCEPROP 1 LASTPIN (525 900) $PN 1
J 0
(537 912);
DISPLAY 0.787234 (537 912);
FORCEPROP 1 LASTPIN (725 900) $PN 2
J 0
(687 912);
DISPLAY 0.787234 (687 912);
FORCEPROP 2 LAST CDS_LIB pure_quanta
J 0
(625 900);
PAINT MONO (625 900);
DISPLAY INVISIBLE (625 900);
FORCEPROP 1 LAST PATH I21
J 0
(575 1050);
DISPLAY 0.978723 (575 1050);
PAINT WHITE (575 1050);
DISPLAY INVISIBLE (575 1050);
FORCEPROP 2 LAST CDS_LOCATION R667
J 0
(575 1100);
DISPLAY 1.021277 (575 1100);
DISPLAY INVISIBLE (575 1100);
FORCEPROP 2 LAST $SEC 1
J 0
(575 1100);
DISPLAY 0.680851 (575 1100);
PAINT MONO (575 1100);
DISPLAY INVISIBLE (575 1100);
FORCEPROP 2 LAST CDS_SEC 1
J 0
(575 1100);
DISPLAY 1.021277 (575 1100);
DISPLAY INVISIBLE (575 1100);
FORCEADD Q_RES..1
(625 1025);
FORCEPROP 1 LAST PART_NUMBER CS00002JB13
J 0
(575 1075);
DISPLAY 0.404255 (575 1075);
DISPLAY INVISIBLE (575 1075);
FORCEPROP 1 LAST VALUE 0
J 2
(775 1025);
DISPLAY 0.510638 (775 1025);
FORCEPROP 1 LAST TOLERANCE 5%
J 0
(800 1025);
DISPLAY 0.510638 (800 1025);
FORCEPROP 1 LAST PACK_TYPE 0402LF
J 0
(575 1100);
DISPLAY 0.404255 (575 1100);
FORCEPROP 1 LAST WATTAGE 1/16W
J 2
(800 1100);
DISPLAY 0.404255 (800 1100);
FORCEPROP 1 LAST MATERIAL EMPTY
J 0
(875 1025);
DISPLAY 0.510638 (875 1025);
PAINT RED (875 1025);
FORCEPROP 1 LAST $LOCATION R666
J 0
(425 1025);
DISPLAY 0.638298 (425 1025);
FORCEPROP 1 LASTPIN (525 1025) $PN 1
J 0
(537 1037);
DISPLAY 0.787234 (537 1037);
FORCEPROP 1 LASTPIN (725 1025) $PN 2
J 0
(687 1037);
DISPLAY 0.787234 (687 1037);
FORCEPROP 2 LAST CDS_LIB pure_quanta
J 0
(625 1025);
PAINT MONO (625 1025);
DISPLAY INVISIBLE (625 1025);
FORCEPROP 1 LAST PATH I22
J 0
(575 1175);
DISPLAY 0.978723 (575 1175);
PAINT WHITE (575 1175);
DISPLAY INVISIBLE (575 1175);
FORCEPROP 2 LAST CDS_LOCATION R666
J 0
(575 1225);
DISPLAY 1.021277 (575 1225);
DISPLAY INVISIBLE (575 1225);
FORCEPROP 2 LAST $SEC 1
J 0
(575 1225);
DISPLAY 0.680851 (575 1225);
PAINT MONO (575 1225);
DISPLAY INVISIBLE (575 1225);
FORCEPROP 2 LAST CDS_SEC 1
J 0
(575 1225);
DISPLAY 1.021277 (575 1225);
DISPLAY INVISIBLE (575 1225);
FORCEADD Q_RES..1
(625 1150);
FORCEPROP 1 LAST PART_NUMBER CS00002JB13
J 0
(575 1200);
DISPLAY 0.404255 (575 1200);
DISPLAY INVISIBLE (575 1200);
FORCEPROP 1 LAST PACK_TYPE 0402LF
J 0
(575 1225);
DISPLAY 0.404255 (575 1225);
FORCEPROP 1 LAST WATTAGE 1/16W
J 2
(800 1225);
DISPLAY 0.404255 (800 1225);
FORCEPROP 1 LAST VALUE 0
J 2
(775 1150);
DISPLAY 0.510638 (775 1150);
FORCEPROP 1 LAST TOLERANCE 5%
J 0
(800 1150);
DISPLAY 0.510638 (800 1150);
FORCEPROP 1 LAST MATERIAL EMPTY
J 0
(875 1150);
DISPLAY 0.510638 (875 1150);
PAINT RED (875 1150);
FORCEPROP 1 LAST $LOCATION R665
J 0
(425 1150);
DISPLAY 0.638298 (425 1150);
FORCEPROP 1 LASTPIN (525 1150) $PN 1
J 0
(537 1162);
DISPLAY 0.787234 (537 1162);
FORCEPROP 1 LASTPIN (725 1150) $PN 2
J 0
(687 1162);
DISPLAY 0.787234 (687 1162);
FORCEPROP 2 LAST CDS_LIB pure_quanta
J 0
(625 1150);
PAINT MONO (625 1150);
DISPLAY INVISIBLE (625 1150);
FORCEPROP 1 LAST PATH I23
J 0
(575 1300);
DISPLAY 0.978723 (575 1300);
PAINT WHITE (575 1300);
DISPLAY INVISIBLE (575 1300);
FORCEPROP 2 LAST CDS_LOCATION R665
J 0
(575 1350);
DISPLAY 1.021277 (575 1350);
DISPLAY INVISIBLE (575 1350);
FORCEPROP 2 LAST $SEC 1
J 0
(575 1350);
DISPLAY 0.680851 (575 1350);
PAINT MONO (575 1350);
DISPLAY INVISIBLE (575 1350);
FORCEPROP 2 LAST CDS_SEC 1
J 0
(575 1350);
DISPLAY 1.021277 (575 1350);
DISPLAY INVISIBLE (575 1350);
FORCEADD UNIVERSAL_GND..1
(1025 1300);
FORCEPROP 3 LASTPIN (1025 1350) SIG_NAME GND\g
J 0
(1035 1360);
DISPLAY 0.659574 (1035 1360);
PAINT MONO (1035 1360);
DISPLAY INVISIBLE (1035 1360);
FORCEPROP 1 LAST HDL_POWER GND
J 1
(1050 1225);
DISPLAY 0.702128 (1050 1225);
PAINT GREEN (1050 1225);
DISPLAY INVISIBLE (1050 1225);
FORCEPROP 2 LAST CDS_LIB logical_power
J 0
(1025 1300);
PAINT MONO (1025 1300);
DISPLAY INVISIBLE (1025 1300);
FORCEPROP 1 LAST PATH I24
J 0
(1100 1300);
DISPLAY 0.872340 (1100 1300);
PAINT AQUA (1100 1300);
DISPLAY INVISIBLE (1100 1300);
FORCEADD Q_CAP..1
(1250 2350);
FORCEPROP 1 LAST PART_NUMBER CH4104K1B00
J 0
(1300 2200);
DISPLAY 0.638298 (1300 2200);
DISPLAY INVISIBLE (1300 2200);
FORCEPROP 1 LAST VALUE 0.1UF
J 0
(1300 2400);
DISPLAY 0.638298 (1300 2400);
FORCEPROP 1 LAST TOLERANCE 10%
J 0
(1300 2300);
DISPLAY 0.638298 (1300 2300);
FORCEPROP 1 LAST MATERIAL X7R
J 0
(1300 2250);
DISPLAY 0.638298 (1300 2250);
FORCEPROP 1 LAST PACK_TYPE 0402
J 0
(1300 2150);
DISPLAY 0.638298 (1300 2150);
FORCEPROP 1 LAST VOLTAGE 25V
J 0
(1300 2350);
DISPLAY 0.638298 (1300 2350);
FORCEPROP 1 LAST $LOCATION C537
J 0
(1300 2450);
DISPLAY 0.978723 (1300 2450);
FORCEPROP 1 LASTPIN (1250 2450) $PN 1
J 0
(1260 2430);
DISPLAY 0.787234 (1260 2430);
FORCEPROP 1 LASTPIN (1250 2250) $PN 2
J 0
(1260 2230);
DISPLAY 0.787234 (1260 2230);
FORCEPROP 2 LAST CDS_LIB pure_quanta
J 0
(1250 2350);
PAINT MONO (1250 2350);
DISPLAY INVISIBLE (1250 2350);
FORCEPROP 1 LAST PATH I25
J 0
(1300 2500);
DISPLAY 0.978723 (1300 2500);
PAINT WHITE (1300 2500);
DISPLAY INVISIBLE (1300 2500);
FORCEPROP 2 LAST CDS_LOCATION C537
J 0
(1300 2550);
DISPLAY 1.021277 (1300 2550);
DISPLAY INVISIBLE (1300 2550);
FORCEPROP 2 LAST $SEC 1
J 0
(1300 2550);
DISPLAY 0.680851 (1300 2550);
PAINT MONO (1300 2550);
DISPLAY INVISIBLE (1300 2550);
FORCEPROP 2 LAST CDS_SEC 1
J 0
(1300 2550);
DISPLAY 1.021277 (1300 2550);
DISPLAY INVISIBLE (1300 2550);
FORCEADD UNIVERSAL_GND..1
(1250 2100);
FORCEPROP 3 LASTPIN (1250 2150) SIG_NAME GND\g
J 0
(1260 2160);
DISPLAY 0.659574 (1260 2160);
PAINT MONO (1260 2160);
DISPLAY INVISIBLE (1260 2160);
FORCEPROP 1 LAST HDL_POWER GND
J 1
(1275 2025);
DISPLAY 0.872340 (1275 2025);
PAINT GREEN (1275 2025);
DISPLAY INVISIBLE (1275 2025);
FORCEPROP 2 LAST CDS_LIB logical_power
J 0
(1250 2100);
PAINT MONO (1250 2100);
DISPLAY INVISIBLE (1250 2100);
FORCEPROP 1 LAST PATH I26
J 0
(1325 2100);
DISPLAY 0.872340 (1325 2100);
PAINT AQUA (1325 2100);
DISPLAY INVISIBLE (1325 2100);
FORCEADD UNIVERSAL_POWER..1
(1025 2675);
FORCEPROP 3 LASTPIN (1025 2625) SIG_NAME P3V3_AUX\g
J 0
(1035 2635);
DISPLAY 0.659574 (1035 2635);
PAINT MONO (1035 2635);
DISPLAY INVISIBLE (1035 2635);
FORCEPROP 1 LAST HDL_POWER P3V3_AUX
J 1
(1025 2725);
DISPLAY 0.702128 (1025 2725);
PAINT GREEN (1025 2725);
FORCEPROP 2 LAST CDS_LIB logical_power
J 0
(1025 2675);
DISPLAY INVISIBLE (1025 2675);
FORCEPROP 1 LAST PATH I27
J 0
(1075 2700);
DISPLAY 0.872340 (1075 2700);
PAINT AQUA (1075 2700);
DISPLAY INVISIBLE (1075 2700);
FORCEADD Q_RES..2
(475 4300);
FORCEPROP 1 LAST PART_NUMBER CS14992FB06
J 0
(515 4125);
DISPLAY 0.638298 (515 4125);
DISPLAY INVISIBLE (515 4125);
FORCEPROP 1 LAST TOLERANCE 1%
J 0
(520 4325);
DISPLAY 0.638298 (520 4325);
FORCEPROP 1 LAST MATERIAL CHIP
J 0
(515 4225);
DISPLAY 0.638298 (515 4225);
FORCEPROP 1 LAST WATTAGE 1/16W
J 0
(515 4275);
DISPLAY 0.638298 (515 4275);
FORCEPROP 1 LAST PACK_TYPE 0402LF
J 0
(515 4175);
DISPLAY 0.638298 (515 4175);
FORCEPROP 1 LAST VALUE 499
J 0
(520 4375);
DISPLAY 0.638298 (520 4375);
FORCEPROP 1 LAST $LOCATION R664
J 0
(520 4425);
DISPLAY 0.978723 (520 4425);
FORCEPROP 1 LASTPIN (475 4400) $PN 1
J 0
(480 4362);
DISPLAY 0.787234 (480 4362);
FORCEPROP 1 LASTPIN (475 4200) $PN 2
J 0
(480 4210);
DISPLAY 0.787234 (480 4210);
FORCEPROP 2 LAST CDS_LIB pure_quanta
J 0
(475 4300);
PAINT MONO (475 4300);
DISPLAY INVISIBLE (475 4300);
FORCEPROP 1 LAST PATH I28
J 0
(525 4475);
DISPLAY 0.978723 (525 4475);
PAINT WHITE (525 4475);
DISPLAY INVISIBLE (525 4475);
FORCEPROP 2 LAST CDS_LOCATION R664
J 0
(525 4525);
DISPLAY 1.021277 (525 4525);
DISPLAY INVISIBLE (525 4525);
FORCEPROP 2 LAST $SEC 1
J 0
(525 4525);
DISPLAY 0.680851 (525 4525);
PAINT MONO (525 4525);
DISPLAY INVISIBLE (525 4525);
FORCEPROP 2 LAST CDS_SEC 1
J 0
(525 4525);
DISPLAY 1.021277 (525 4525);
DISPLAY INVISIBLE (525 4525);
FORCEADD Q_RES..2
(725 4300);
FORCEPROP 1 LAST PART_NUMBER CS14992FB06
J 0
(765 4125);
DISPLAY 0.510638 (765 4125);
DISPLAY INVISIBLE (765 4125);
FORCEPROP 1 LAST WATTAGE 1/16W
J 0
(765 4275);
DISPLAY 0.638298 (765 4275);
FORCEPROP 1 LAST MATERIAL CHIP
J 0
(765 4225);
DISPLAY 0.638298 (765 4225);
FORCEPROP 1 LAST TOLERANCE 1%
J 0
(770 4325);
DISPLAY 0.638298 (770 4325);
FORCEPROP 1 LAST VALUE 499
J 0
(770 4375);
DISPLAY 0.638298 (770 4375);
FORCEPROP 1 LAST PACK_TYPE 0402LF
J 0
(765 4175);
DISPLAY 0.638298 (765 4175);
FORCEPROP 1 LAST $LOCATION R669
J 0
(770 4425);
DISPLAY 0.978723 (770 4425);
FORCEPROP 1 LASTPIN (725 4400) $PN 1
J 0
(730 4362);
DISPLAY 0.787234 (730 4362);
FORCEPROP 1 LASTPIN (725 4200) $PN 2
J 0
(730 4210);
DISPLAY 0.787234 (730 4210);
FORCEPROP 2 LAST CDS_LIB pure_quanta
J 0
(725 4300);
PAINT MONO (725 4300);
DISPLAY INVISIBLE (725 4300);
FORCEPROP 1 LAST PATH I29
J 0
(775 4475);
DISPLAY 0.978723 (775 4475);
PAINT WHITE (775 4475);
DISPLAY INVISIBLE (775 4475);
FORCEPROP 2 LAST CDS_LOCATION R669
J 0
(775 4525);
DISPLAY 1.021277 (775 4525);
DISPLAY INVISIBLE (775 4525);
FORCEPROP 2 LAST $SEC 1
J 0
(775 4525);
DISPLAY 0.680851 (775 4525);
PAINT MONO (775 4525);
DISPLAY INVISIBLE (775 4525);
FORCEPROP 2 LAST CDS_SEC 1
J 0
(775 4525);
DISPLAY 1.021277 (775 4525);
DISPLAY INVISIBLE (775 4525);
FORCEADD UNIVERSAL_GND..1
(-1050 1000);
FORCEPROP 3 LASTPIN (-1050 1050) SIG_NAME GND\g
J 0
(-1040 1060);
DISPLAY 0.659574 (-1040 1060);
PAINT MONO (-1040 1060);
DISPLAY INVISIBLE (-1040 1060);
FORCEPROP 1 LAST HDL_POWER GND
J 1
(-1025 925);
DISPLAY 0.702128 (-1025 925);
PAINT GREEN (-1025 925);
DISPLAY INVISIBLE (-1025 925);
FORCEPROP 2 LAST CDS_LIB logical_power
J 0
(-1050 1000);
PAINT MONO (-1050 1000);
DISPLAY INVISIBLE (-1050 1000);
FORCEPROP 1 LAST PATH I3
J 0
(-975 1000);
DISPLAY 0.872340 (-975 1000);
PAINT AQUA (-975 1000);
DISPLAY INVISIBLE (-975 1000);
FORCEADD Q_RES..1
(1125 3675);
FORCEPROP 1 LAST PART_NUMBER CS00002JB13
J 0
(1250 3700);
DISPLAY 0.319149 (1250 3700);
DISPLAY INVISIBLE (1250 3700);
FORCEPROP 1 LAST PACK_TYPE 0402LF
J 0
(1250 3725);
DISPLAY 0.319149 (1250 3725);
FORCEPROP 1 LAST TOLERANCE 5%
J 0
(1300 3675);
DISPLAY 0.404255 (1300 3675);
FORCEPROP 1 LAST MATERIAL CHIP
J 0
(1375 3675);
DISPLAY 0.404255 (1375 3675);
FORCEPROP 1 LAST WATTAGE 1/16W
J 2
(1425 3725);
DISPLAY 0.319149 (1425 3725);
FORCEPROP 1 LAST VALUE 0
J 2
(1275 3675);
DISPLAY 0.404255 (1275 3675);
FORCEPROP 1 LAST LOCATION R672
J 0
(925 3675);
DISPLAY 0.808511 (925 3675);
FORCEPROP 1 LASTPIN (1025 3675) $PN 1
J 0
(1037 3687);
DISPLAY 0.787234 (1037 3687);
PAINT MONO (1037 3687);
FORCEPROP 1 LASTPIN (1225 3675) $PN 2
J 0
(1187 3687);
DISPLAY 0.787234 (1187 3687);
PAINT MONO (1187 3687);
FORCEPROP 2 LAST CDS_LIB pure_quanta
J 0
(1125 3675);
DISPLAY INVISIBLE (1125 3675);
FORCEPROP 1 LAST PATH I30
J 0
(1075 3825);
DISPLAY 0.978723 (1075 3825);
PAINT WHITE (1075 3825);
DISPLAY INVISIBLE (1075 3825);
FORCEPROP 0 LAST $SEC 1
J 0
(1425 3750);
DISPLAY 0.680851 (1425 3750);
PAINT MONO (1425 3750);
DISPLAY INVISIBLE (1425 3750);
FORCEPROP 0 LAST CDS_SEC 1
J 0
(1425 3750);
DISPLAY 1.021277 (1425 3750);
DISPLAY INVISIBLE (1425 3750);
FORCEADD Q_RES..1
(1125 3625);
FORCEPROP 1 LAST PART_NUMBER CS03322FB03
J 0
(1075 3675);
DISPLAY 0.404255 (1075 3675);
DISPLAY INVISIBLE (1075 3675);
FORCEPROP 1 LAST VALUE 33.2
J 2
(1325 3625);
DISPLAY 0.510638 (1325 3625);
FORCEPROP 1 LAST PACK_TYPE 0402LF
J 0
(1425 3625);
DISPLAY 0.510638 (1425 3625);
FORCEPROP 1 LAST TOLERANCE 1%
J 0
(1350 3625);
DISPLAY 0.510638 (1350 3625);
FORCEPROP 1 LAST $LOCATION R673
J 0
(925 3625);
DISPLAY 0.787234 (925 3625);
FORCEPROP 1 LASTPIN (1025 3625) $PN 1
J 0
(1037 3637);
DISPLAY 0.787234 (1037 3637);
FORCEPROP 1 LASTPIN (1225 3625) $PN 2
J 0
(1187 3637);
DISPLAY 0.787234 (1187 3637);
FORCEPROP 2 LAST CDS_LIB pure_quanta
J 0
(1125 3625);
PAINT MONO (1125 3625);
DISPLAY INVISIBLE (1125 3625);
FORCEPROP 1 LAST MATERIAL CHIP
J 0
(1075 3700);
DISPLAY 0.404255 (1075 3700);
DISPLAY INVISIBLE (1075 3700);
FORCEPROP 1 LAST WATTAGE 1/16W
J 2
(1300 3700);
DISPLAY 0.404255 (1300 3700);
DISPLAY INVISIBLE (1300 3700);
FORCEPROP 1 LAST PATH I31
J 0
(1075 3775);
DISPLAY 0.978723 (1075 3775);
PAINT WHITE (1075 3775);
DISPLAY INVISIBLE (1075 3775);
FORCEPROP 2 LAST CDS_LOCATION R673
J 0
(1075 3825);
DISPLAY 1.021277 (1075 3825);
DISPLAY INVISIBLE (1075 3825);
FORCEPROP 2 LAST $SEC 1
J 0
(1075 3825);
DISPLAY 0.680851 (1075 3825);
PAINT MONO (1075 3825);
DISPLAY INVISIBLE (1075 3825);
FORCEPROP 2 LAST CDS_SEC 1
J 0
(1075 3825);
DISPLAY 1.021277 (1075 3825);
DISPLAY INVISIBLE (1075 3825);
FORCEADD Q_RES..1
(1125 3975);
FORCEPROP 1 LAST PART_NUMBER CS00002JB13
J 0
(1250 4000);
DISPLAY 0.319149 (1250 4000);
DISPLAY INVISIBLE (1250 4000);
FORCEPROP 1 LAST VALUE 0
J 2
(1275 3975);
DISPLAY 0.404255 (1275 3975);
FORCEPROP 1 LAST PACK_TYPE 0402LF
J 0
(1250 4025);
DISPLAY 0.319149 (1250 4025);
FORCEPROP 1 LAST WATTAGE 1/16W
J 2
(1425 4025);
DISPLAY 0.319149 (1425 4025);
FORCEPROP 1 LAST MATERIAL CHIP
J 0
(1375 3975);
DISPLAY 0.404255 (1375 3975);
FORCEPROP 1 LAST TOLERANCE 5%
J 0
(1300 3975);
DISPLAY 0.404255 (1300 3975);
FORCEPROP 1 LAST LOCATION R670
J 0
(925 3975);
DISPLAY 0.787234 (925 3975);
FORCEPROP 1 LASTPIN (1025 3975) $PN 1
J 0
(1037 3987);
DISPLAY 0.787234 (1037 3987);
PAINT MONO (1037 3987);
FORCEPROP 1 LASTPIN (1225 3975) $PN 2
J 0
(1187 3987);
DISPLAY 0.787234 (1187 3987);
PAINT MONO (1187 3987);
FORCEPROP 2 LAST CDS_LIB pure_quanta
J 0
(1125 3975);
DISPLAY INVISIBLE (1125 3975);
FORCEPROP 1 LAST PATH I32
J 0
(1075 4125);
DISPLAY 0.978723 (1075 4125);
PAINT WHITE (1075 4125);
DISPLAY INVISIBLE (1075 4125);
FORCEPROP 0 LAST $SEC 1
J 0
(1425 4050);
DISPLAY 0.680851 (1425 4050);
PAINT MONO (1425 4050);
DISPLAY INVISIBLE (1425 4050);
FORCEPROP 0 LAST CDS_SEC 1
J 0
(1425 4050);
DISPLAY 1.021277 (1425 4050);
DISPLAY INVISIBLE (1425 4050);
FORCEADD Q_RES..1
(1125 3925);
FORCEPROP 1 LAST PART_NUMBER CS03322FB03
J 0
(1075 3975);
DISPLAY 0.404255 (1075 3975);
DISPLAY INVISIBLE (1075 3975);
FORCEPROP 1 LAST VALUE 33.2
J 2
(1325 3925);
DISPLAY 0.510638 (1325 3925);
FORCEPROP 1 LAST PACK_TYPE 0402LF
J 0
(1425 3925);
DISPLAY 0.510638 (1425 3925);
FORCEPROP 1 LAST TOLERANCE 1%
J 0
(1350 3925);
DISPLAY 0.510638 (1350 3925);
FORCEPROP 1 LAST $LOCATION R671
J 0
(925 3925);
DISPLAY 0.787234 (925 3925);
FORCEPROP 1 LASTPIN (1025 3925) $PN 1
J 0
(1037 3937);
DISPLAY 0.787234 (1037 3937);
FORCEPROP 1 LASTPIN (1225 3925) $PN 2
J 0
(1187 3937);
DISPLAY 0.787234 (1187 3937);
FORCEPROP 2 LAST CDS_LIB pure_quanta
J 0
(1125 3925);
PAINT MONO (1125 3925);
DISPLAY INVISIBLE (1125 3925);
FORCEPROP 1 LAST WATTAGE 1/16W
J 2
(1300 4000);
DISPLAY 0.404255 (1300 4000);
DISPLAY INVISIBLE (1300 4000);
FORCEPROP 1 LAST MATERIAL CHIP
J 0
(1075 4000);
DISPLAY 0.404255 (1075 4000);
DISPLAY INVISIBLE (1075 4000);
FORCEPROP 1 LAST PATH I33
J 0
(1075 4075);
DISPLAY 0.978723 (1075 4075);
PAINT WHITE (1075 4075);
DISPLAY INVISIBLE (1075 4075);
FORCEPROP 2 LAST CDS_LOCATION R671
J 0
(1075 4125);
DISPLAY 1.021277 (1075 4125);
DISPLAY INVISIBLE (1075 4125);
FORCEPROP 2 LAST $SEC 1
J 0
(1075 4125);
DISPLAY 0.680851 (1075 4125);
PAINT MONO (1075 4125);
DISPLAY INVISIBLE (1075 4125);
FORCEPROP 2 LAST CDS_SEC 1
J 0
(1075 4125);
DISPLAY 1.021277 (1075 4125);
DISPLAY INVISIBLE (1075 4125);
FORCEADD Q_RES..1
(2750 1575);
FORCEPROP 1 LAST PART_NUMBER CS03322FB03
J 0
(2700 1625);
DISPLAY 0.404255 (2700 1625);
DISPLAY INVISIBLE (2700 1625);
FORCEPROP 1 LAST VALUE 33.2
J 2
(2900 1575);
DISPLAY 0.510638 (2900 1575);
FORCEPROP 1 LAST TOLERANCE 1%
J 0
(2925 1575);
DISPLAY 0.510638 (2925 1575);
FORCEPROP 1 LAST $LOCATION R677
J 0
(2550 1575);
DISPLAY 0.638298 (2550 1575);
FORCEPROP 1 LASTPIN (2650 1575) $PN 1
J 0
(2662 1587);
DISPLAY 0.787234 (2662 1587);
FORCEPROP 1 LASTPIN (2850 1575) $PN 2
J 0
(2812 1587);
DISPLAY 0.787234 (2812 1587);
FORCEPROP 1 LAST PACK_TYPE 0402LF
J 0
(3000 1575);
DISPLAY 0.510638 (3000 1575);
DISPLAY INVISIBLE (3000 1575);
FORCEPROP 1 LAST MATERIAL CHIP
J 0
(2700 1650);
DISPLAY 0.404255 (2700 1650);
DISPLAY INVISIBLE (2700 1650);
FORCEPROP 1 LAST WATTAGE 1/16W
J 2
(2925 1650);
DISPLAY 0.404255 (2925 1650);
DISPLAY INVISIBLE (2925 1650);
FORCEPROP 2 LAST CDS_LIB pure_quanta
J 0
(2750 1575);
PAINT MONO (2750 1575);
DISPLAY INVISIBLE (2750 1575);
FORCEPROP 1 LAST PATH I34
J 0
(2700 1725);
DISPLAY 0.978723 (2700 1725);
PAINT WHITE (2700 1725);
DISPLAY INVISIBLE (2700 1725);
FORCEPROP 2 LAST CDS_LOCATION R677
J 0
(2700 1775);
DISPLAY 1.021277 (2700 1775);
DISPLAY INVISIBLE (2700 1775);
FORCEPROP 2 LAST $SEC 1
J 0
(2700 1775);
DISPLAY 0.680851 (2700 1775);
PAINT MONO (2700 1775);
DISPLAY INVISIBLE (2700 1775);
FORCEPROP 2 LAST CDS_SEC 1
J 0
(2700 1775);
DISPLAY 1.021277 (2700 1775);
DISPLAY INVISIBLE (2700 1775);
FORCEADD Q_RES..1
(2750 1725);
FORCEPROP 1 LAST PART_NUMBER CS00002JB13
J 0
(2700 1775);
DISPLAY 0.404255 (2700 1775);
DISPLAY INVISIBLE (2700 1775);
FORCEPROP 1 LAST TOLERANCE 5%
J 0
(2925 1725);
DISPLAY 0.510638 (2925 1725);
FORCEPROP 1 LAST VALUE 0
J 2
(2900 1725);
DISPLAY 0.510638 (2900 1725);
FORCEPROP 1 LAST $LOCATION R676
J 0
(2550 1725);
DISPLAY 0.638298 (2550 1725);
FORCEPROP 1 LASTPIN (2650 1725) $PN 1
J 0
(2662 1737);
DISPLAY 0.787234 (2662 1737);
FORCEPROP 1 LASTPIN (2850 1725) $PN 2
J 0
(2812 1737);
DISPLAY 0.787234 (2812 1737);
FORCEPROP 1 LAST MATERIAL CHIP
J 0
(2700 1800);
DISPLAY 0.404255 (2700 1800);
DISPLAY INVISIBLE (2700 1800);
FORCEPROP 1 LAST WATTAGE 1/16W
J 2
(2925 1800);
DISPLAY 0.404255 (2925 1800);
DISPLAY INVISIBLE (2925 1800);
FORCEPROP 2 LAST CDS_LIB pure_quanta
J 0
(2750 1725);
PAINT MONO (2750 1725);
DISPLAY INVISIBLE (2750 1725);
FORCEPROP 1 LAST PACK_TYPE 0402LF
J 0
(3000 1725);
DISPLAY 0.510638 (3000 1725);
DISPLAY INVISIBLE (3000 1725);
FORCEPROP 1 LAST PATH I35
J 0
(2700 1875);
DISPLAY 0.978723 (2700 1875);
PAINT WHITE (2700 1875);
DISPLAY INVISIBLE (2700 1875);
FORCEPROP 2 LAST CDS_LOCATION R676
J 0
(2700 1925);
DISPLAY 1.021277 (2700 1925);
DISPLAY INVISIBLE (2700 1925);
FORCEPROP 2 LAST $SEC 1
J 0
(2700 1925);
DISPLAY 0.680851 (2700 1925);
PAINT MONO (2700 1925);
DISPLAY INVISIBLE (2700 1925);
FORCEPROP 2 LAST CDS_SEC 1
J 0
(2700 1925);
DISPLAY 1.021277 (2700 1925);
DISPLAY INVISIBLE (2700 1925);
FORCEADD Q_RES..1
(2750 1875);
FORCEPROP 1 LAST PART_NUMBER CS03322FB03
J 0
(2700 1925);
DISPLAY 0.404255 (2700 1925);
DISPLAY INVISIBLE (2700 1925);
FORCEPROP 1 LAST VALUE 33.2
J 2
(2900 1875);
DISPLAY 0.510638 (2900 1875);
FORCEPROP 1 LAST TOLERANCE 1%
J 0
(2925 1875);
DISPLAY 0.510638 (2925 1875);
FORCEPROP 1 LAST $LOCATION R675
J 0
(2550 1875);
DISPLAY 0.638298 (2550 1875);
FORCEPROP 1 LASTPIN (2650 1875) $PN 1
J 0
(2662 1887);
DISPLAY 0.787234 (2662 1887);
FORCEPROP 1 LASTPIN (2850 1875) $PN 2
J 0
(2812 1887);
DISPLAY 0.787234 (2812 1887);
FORCEPROP 1 LAST PACK_TYPE 0402LF
J 0
(3000 1875);
DISPLAY 0.510638 (3000 1875);
DISPLAY INVISIBLE (3000 1875);
FORCEPROP 2 LAST CDS_LIB pure_quanta
J 0
(2750 1875);
PAINT MONO (2750 1875);
DISPLAY INVISIBLE (2750 1875);
FORCEPROP 1 LAST WATTAGE 1/16W
J 2
(2925 1950);
DISPLAY 0.404255 (2925 1950);
DISPLAY INVISIBLE (2925 1950);
FORCEPROP 1 LAST MATERIAL CHIP
J 0
(2700 1950);
DISPLAY 0.404255 (2700 1950);
DISPLAY INVISIBLE (2700 1950);
FORCEPROP 1 LAST PATH I36
J 0
(2700 2025);
DISPLAY 0.978723 (2700 2025);
PAINT WHITE (2700 2025);
DISPLAY INVISIBLE (2700 2025);
FORCEPROP 2 LAST CDS_LOCATION R675
J 0
(2700 2075);
DISPLAY 1.021277 (2700 2075);
DISPLAY INVISIBLE (2700 2075);
FORCEPROP 2 LAST $SEC 1
J 0
(2700 2075);
DISPLAY 0.680851 (2700 2075);
PAINT MONO (2700 2075);
DISPLAY INVISIBLE (2700 2075);
FORCEPROP 2 LAST CDS_SEC 1
J 0
(2700 2075);
DISPLAY 1.021277 (2700 2075);
DISPLAY INVISIBLE (2700 2075);
FORCEADD Q_RES..1
(2750 2025);
FORCEPROP 1 LAST PART_NUMBER CS00002JB13
J 0
(2700 2075);
DISPLAY 0.404255 (2700 2075);
DISPLAY INVISIBLE (2700 2075);
FORCEPROP 1 LAST MATERIAL CHIP
J 0
(2700 2100);
DISPLAY 0.404255 (2700 2100);
FORCEPROP 1 LAST PACK_TYPE 0402LF
J 0
(2700 2125);
DISPLAY 0.404255 (2700 2125);
FORCEPROP 1 LAST WATTAGE 1/16W
J 2
(2925 2100);
DISPLAY 0.404255 (2925 2100);
FORCEPROP 1 LAST VALUE 0
J 2
(2900 2025);
DISPLAY 0.510638 (2900 2025);
FORCEPROP 1 LAST TOLERANCE 5%
J 0
(2925 2025);
DISPLAY 0.510638 (2925 2025);
FORCEPROP 1 LAST $LOCATION R674
J 0
(2550 2025);
DISPLAY 0.638298 (2550 2025);
FORCEPROP 1 LASTPIN (2650 2025) $PN 1
J 0
(2662 2037);
DISPLAY 0.787234 (2662 2037);
FORCEPROP 1 LASTPIN (2850 2025) $PN 2
J 0
(2812 2037);
DISPLAY 0.787234 (2812 2037);
FORCEPROP 2 LAST CDS_LIB pure_quanta
J 0
(2750 2025);
PAINT MONO (2750 2025);
DISPLAY INVISIBLE (2750 2025);
FORCEPROP 1 LAST PATH I37
J 0
(2700 2175);
DISPLAY 0.978723 (2700 2175);
PAINT WHITE (2700 2175);
DISPLAY INVISIBLE (2700 2175);
FORCEPROP 2 LAST CDS_LOCATION R674
J 0
(2700 2225);
DISPLAY 1.021277 (2700 2225);
DISPLAY INVISIBLE (2700 2225);
FORCEPROP 2 LAST $SEC 1
J 0
(2700 2225);
DISPLAY 0.680851 (2700 2225);
PAINT MONO (2700 2225);
DISPLAY INVISIBLE (2700 2225);
FORCEPROP 2 LAST CDS_SEC 1
J 0
(2700 2225);
DISPLAY 1.021277 (2700 2225);
DISPLAY INVISIBLE (2700 2225);
FORCEADD OFFPAGE..3
(4100 1575);
FORCEPROP 2 LAST $XR0 106 
J 0
(4314 1575);
DISPLAY 0.638298 (4314 1575);
PAINT MONO (4314 1575);
FORCEPROP 2 LAST $XR1 107 
J 0
(4434 1575);
DISPLAY 0.638298 (4434 1575);
PAINT MONO (4434 1575);
FORCEPROP 2 LAST $XR2 108 
J 0
(4554 1575);
DISPLAY 0.638298 (4554 1575);
PAINT MONO (4554 1575);
FORCEPROP 2 LAST $XR3 109 
J 0
(4674 1575);
DISPLAY 0.638298 (4674 1575);
PAINT MONO (4674 1575);
FORCEPROP 2 LAST $XR4 110 
J 0
(4794 1575);
DISPLAY 0.638298 (4794 1575);
PAINT MONO (4794 1575);
FORCEPROP 2 LAST $XR5 111 
J 0
(4914 1575);
DISPLAY 0.638298 (4914 1575);
PAINT MONO (4914 1575);
FORCEPROP 2 LAST $XR6 112 
J 0
(5034 1575);
DISPLAY 0.638298 (5034 1575);
PAINT MONO (5034 1575);
FORCEPROP 2 LAST $XR7 113 
J 0
(5154 1575);
DISPLAY 0.638298 (5154 1575);
PAINT MONO (5154 1575);
FORCEPROP 1 LAST COMMENT_BODY TRUE
J 0
(4050 1475);
DISPLAY 0.872340 (4050 1475);
PAINT GREEN (4050 1475);
DISPLAY INVISIBLE (4050 1475);
FORCEPROP 1 LAST OFFPAGE TRUE
J 0
(4425 1450);
DISPLAY 0.872340 (4425 1450);
PAINT GREEN (4425 1450);
DISPLAY INVISIBLE (4425 1450);
FORCEPROP 2 LAST CDS_LIB standard
J 0
(4100 1575);
PAINT MONO (4100 1575);
DISPLAY INVISIBLE (4100 1575);
FORCEPROP 2 LAST PATH I38
J 0
(5175 1625);
DISPLAY 1.021277 (5175 1625);
DISPLAY INVISIBLE (5175 1625);
FORCEADD OFFPAGE..2
(4100 1725);
FORCEPROP 2 LAST $XR0 106 
J 0
(4289 1725);
DISPLAY 0.638298 (4289 1725);
PAINT MONO (4289 1725);
FORCEPROP 2 LAST $XR1 107 
J 0
(4409 1725);
DISPLAY 0.638298 (4409 1725);
PAINT MONO (4409 1725);
FORCEPROP 2 LAST $XR2 108 
J 0
(4529 1725);
DISPLAY 0.638298 (4529 1725);
PAINT MONO (4529 1725);
FORCEPROP 2 LAST $XR3 109 
J 0
(4649 1725);
DISPLAY 0.638298 (4649 1725);
PAINT MONO (4649 1725);
FORCEPROP 2 LAST $XR4 110 
J 0
(4769 1725);
DISPLAY 0.638298 (4769 1725);
PAINT MONO (4769 1725);
FORCEPROP 2 LAST $XR5 111 
J 0
(4889 1725);
DISPLAY 0.638298 (4889 1725);
PAINT MONO (4889 1725);
FORCEPROP 2 LAST $XR6 112 
J 0
(5009 1725);
DISPLAY 0.638298 (5009 1725);
PAINT MONO (5009 1725);
FORCEPROP 2 LAST $XR7 113 
J 0
(5129 1725);
DISPLAY 0.638298 (5129 1725);
PAINT MONO (5129 1725);
FORCEPROP 1 LAST COMMENT_BODY TRUE
J 0
(4055 1630);
DISPLAY 0.872340 (4055 1630);
PAINT GREEN (4055 1630);
DISPLAY INVISIBLE (4055 1630);
FORCEPROP 1 LAST OFFPAGE TRUE
J 0
(4425 1600);
DISPLAY 0.872340 (4425 1600);
PAINT GREEN (4425 1600);
DISPLAY INVISIBLE (4425 1600);
FORCEPROP 2 LAST CDS_LIB standard
J 0
(4100 1725);
PAINT MONO (4100 1725);
DISPLAY INVISIBLE (4100 1725);
FORCEPROP 2 LAST PATH I39
J 0
(5150 1775);
DISPLAY 1.021277 (5150 1775);
DISPLAY INVISIBLE (5150 1775);
FORCEADD Q_RES..2
(-1050 1225);
FORCEPROP 1 LAST PART_NUMBER CS21002FB06
J 0
(-1010 1100);
DISPLAY 0.638298 (-1010 1100);
DISPLAY INVISIBLE (-1010 1100);
FORCEPROP 1 LAST WATTAGE 1/16W
J 0
(-1010 1200);
DISPLAY 0.638298 (-1010 1200);
FORCEPROP 1 LAST MATERIAL CHIP
J 0
(-1010 1150);
DISPLAY 0.638298 (-1010 1150);
FORCEPROP 1 LAST PACK_TYPE 0402LF
J 0
(-1010 1050);
DISPLAY 0.638298 (-1010 1050);
FORCEPROP 1 LAST VALUE 1K
J 0
(-1005 1300);
DISPLAY 0.638298 (-1005 1300);
FORCEPROP 1 LAST TOLERANCE 1%
J 0
(-1005 1250);
DISPLAY 0.638298 (-1005 1250);
FORCEPROP 1 LAST $LOCATION R661
J 0
(-1005 1350);
DISPLAY 0.978723 (-1005 1350);
FORCEPROP 1 LASTPIN (-1050 1325) $PN 1
J 0
(-1045 1287);
DISPLAY 0.787234 (-1045 1287);
FORCEPROP 1 LASTPIN (-1050 1125) $PN 2
J 0
(-1045 1135);
DISPLAY 0.787234 (-1045 1135);
FORCEPROP 2 LAST CDS_LIB pure_quanta
J 0
(-1050 1225);
PAINT MONO (-1050 1225);
DISPLAY INVISIBLE (-1050 1225);
FORCEPROP 1 LAST PATH I4
J 0
(-1000 1400);
DISPLAY 0.978723 (-1000 1400);
PAINT WHITE (-1000 1400);
DISPLAY INVISIBLE (-1000 1400);
FORCEPROP 2 LAST CDS_LOCATION R661
J 0
(-1000 1450);
DISPLAY 1.021277 (-1000 1450);
DISPLAY INVISIBLE (-1000 1450);
FORCEPROP 2 LAST $SEC 1
J 0
(-1000 1450);
DISPLAY 0.680851 (-1000 1450);
PAINT MONO (-1000 1450);
DISPLAY INVISIBLE (-1000 1450);
FORCEPROP 2 LAST CDS_SEC 1
J 0
(-1000 1450);
DISPLAY 1.021277 (-1000 1450);
DISPLAY INVISIBLE (-1000 1450);
FORCEADD OFFPAGE..3
(4100 1875);
FORCEPROP 2 LAST $XR0 98 
J 0
(4314 1875);
DISPLAY 0.638298 (4314 1875);
PAINT MONO (4314 1875);
FORCEPROP 2 LAST $XR1 99 
J 0
(4404 1875);
DISPLAY 0.638298 (4404 1875);
PAINT MONO (4404 1875);
FORCEPROP 2 LAST $XR2 100 
J 0
(4494 1875);
DISPLAY 0.638298 (4494 1875);
PAINT MONO (4494 1875);
FORCEPROP 2 LAST $XR3 101 
J 0
(4614 1875);
DISPLAY 0.638298 (4614 1875);
PAINT MONO (4614 1875);
FORCEPROP 2 LAST $XR4 102 
J 0
(4734 1875);
DISPLAY 0.638298 (4734 1875);
PAINT MONO (4734 1875);
FORCEPROP 2 LAST $XR5 103 
J 0
(4854 1875);
DISPLAY 0.638298 (4854 1875);
PAINT MONO (4854 1875);
FORCEPROP 2 LAST $XR6 104 
J 0
(4974 1875);
DISPLAY 0.638298 (4974 1875);
PAINT MONO (4974 1875);
FORCEPROP 2 LAST $XR7 105 
J 0
(5094 1875);
DISPLAY 0.638298 (5094 1875);
PAINT MONO (5094 1875);
FORCEPROP 1 LAST COMMENT_BODY TRUE
J 0
(4050 1775);
DISPLAY 0.872340 (4050 1775);
PAINT GREEN (4050 1775);
DISPLAY INVISIBLE (4050 1775);
FORCEPROP 1 LAST OFFPAGE TRUE
J 0
(4425 1750);
DISPLAY 0.872340 (4425 1750);
PAINT GREEN (4425 1750);
DISPLAY INVISIBLE (4425 1750);
FORCEPROP 2 LAST CDS_LIB standard
J 0
(4100 1875);
PAINT MONO (4100 1875);
DISPLAY INVISIBLE (4100 1875);
FORCEPROP 2 LAST PATH I40
J 0
(5100 1925);
DISPLAY 1.021277 (5100 1925);
DISPLAY INVISIBLE (5100 1925);
FORCEADD OFFPAGE..2
(4100 2025);
FORCEPROP 2 LAST $XR0 98 
J 0
(4289 2025);
DISPLAY 0.638298 (4289 2025);
PAINT MONO (4289 2025);
FORCEPROP 2 LAST $XR1 99 
J 0
(4379 2025);
DISPLAY 0.638298 (4379 2025);
PAINT MONO (4379 2025);
FORCEPROP 2 LAST $XR2 100 
J 0
(4469 2025);
DISPLAY 0.638298 (4469 2025);
PAINT MONO (4469 2025);
FORCEPROP 2 LAST $XR3 101 
J 0
(4589 2025);
DISPLAY 0.638298 (4589 2025);
PAINT MONO (4589 2025);
FORCEPROP 2 LAST $XR4 102 
J 0
(4709 2025);
DISPLAY 0.638298 (4709 2025);
PAINT MONO (4709 2025);
FORCEPROP 2 LAST $XR5 103 
J 0
(4829 2025);
DISPLAY 0.638298 (4829 2025);
PAINT MONO (4829 2025);
FORCEPROP 2 LAST $XR6 104 
J 0
(4949 2025);
DISPLAY 0.638298 (4949 2025);
PAINT MONO (4949 2025);
FORCEPROP 2 LAST $XR7 105 
J 0
(5069 2025);
DISPLAY 0.638298 (5069 2025);
PAINT MONO (5069 2025);
FORCEPROP 1 LAST COMMENT_BODY TRUE
J 0
(4055 1930);
DISPLAY 0.872340 (4055 1930);
PAINT GREEN (4055 1930);
DISPLAY INVISIBLE (4055 1930);
FORCEPROP 1 LAST OFFPAGE TRUE
J 0
(4425 1900);
DISPLAY 0.872340 (4425 1900);
PAINT GREEN (4425 1900);
DISPLAY INVISIBLE (4425 1900);
FORCEPROP 2 LAST CDS_LIB standard
J 0
(4100 2025);
PAINT MONO (4100 2025);
DISPLAY INVISIBLE (4100 2025);
FORCEPROP 2 LAST PATH I41
J 0
(5075 2075);
DISPLAY 1.021277 (5075 2075);
DISPLAY INVISIBLE (5075 2075);
FORCEADD OFFPAGE..3
(2875 3625);
FORCEPROP 2 LAST $XR0 230 
J 0
(3089 3625);
DISPLAY 0.638298 (3089 3625);
PAINT MONO (3089 3625);
FORCEPROP 1 LAST COMMENT_BODY TRUE
J 0
(2825 3525);
DISPLAY 0.872340 (2825 3525);
PAINT GREEN (2825 3525);
DISPLAY INVISIBLE (2825 3525);
FORCEPROP 1 LAST OFFPAGE TRUE
J 0
(3200 3500);
DISPLAY 0.872340 (3200 3500);
PAINT GREEN (3200 3500);
DISPLAY INVISIBLE (3200 3500);
FORCEPROP 2 LAST CDS_LIB standard
J 0
(2875 3625);
PAINT MONO (2875 3625);
DISPLAY INVISIBLE (2875 3625);
FORCEPROP 2 LAST PATH I42
J 0
(3100 3675);
DISPLAY 1.021277 (3100 3675);
DISPLAY INVISIBLE (3100 3675);
FORCEADD OFFPAGE..2
(2875 3675);
FORCEPROP 2 LAST $XR0 230 
J 0
(3064 3675);
DISPLAY 0.638298 (3064 3675);
PAINT MONO (3064 3675);
FORCEPROP 1 LAST COMMENT_BODY TRUE
J 0
(2830 3580);
DISPLAY 0.872340 (2830 3580);
PAINT GREEN (2830 3580);
DISPLAY INVISIBLE (2830 3580);
FORCEPROP 1 LAST OFFPAGE TRUE
J 0
(3200 3550);
DISPLAY 0.872340 (3200 3550);
PAINT GREEN (3200 3550);
DISPLAY INVISIBLE (3200 3550);
FORCEPROP 2 LAST CDS_LIB standard
J 0
(2875 3675);
PAINT MONO (2875 3675);
DISPLAY INVISIBLE (2875 3675);
FORCEPROP 2 LAST PATH I43
J 0
(3075 3725);
DISPLAY 1.021277 (3075 3725);
DISPLAY INVISIBLE (3075 3725);
FORCEADD OFFPAGE..2
(2875 3975);
FORCEPROP 2 LAST $XR0 230 
J 0
(3064 3975);
DISPLAY 0.638298 (3064 3975);
PAINT MONO (3064 3975);
FORCEPROP 1 LAST COMMENT_BODY TRUE
J 0
(2830 3880);
DISPLAY 0.872340 (2830 3880);
PAINT GREEN (2830 3880);
DISPLAY INVISIBLE (2830 3880);
FORCEPROP 1 LAST OFFPAGE TRUE
J 0
(3200 3850);
DISPLAY 0.872340 (3200 3850);
PAINT GREEN (3200 3850);
DISPLAY INVISIBLE (3200 3850);
FORCEPROP 2 LAST CDS_LIB standard
J 0
(2875 3975);
PAINT MONO (2875 3975);
DISPLAY INVISIBLE (2875 3975);
FORCEPROP 2 LAST PATH I44
J 0
(3075 4025);
DISPLAY 1.021277 (3075 4025);
DISPLAY INVISIBLE (3075 4025);
FORCEADD OFFPAGE..3
(2875 3925);
FORCEPROP 2 LAST $XR0 230 
J 0
(3089 3925);
DISPLAY 0.638298 (3089 3925);
PAINT MONO (3089 3925);
FORCEPROP 1 LAST COMMENT_BODY TRUE
J 0
(2825 3825);
DISPLAY 0.872340 (2825 3825);
PAINT GREEN (2825 3825);
DISPLAY INVISIBLE (2825 3825);
FORCEPROP 1 LAST OFFPAGE TRUE
J 0
(3200 3800);
DISPLAY 0.872340 (3200 3800);
PAINT GREEN (3200 3800);
DISPLAY INVISIBLE (3200 3800);
FORCEPROP 2 LAST CDS_LIB standard
J 0
(2875 3925);
PAINT MONO (2875 3925);
DISPLAY INVISIBLE (2875 3925);
FORCEPROP 2 LAST PATH I45
J 0
(3100 3975);
DISPLAY 1.021277 (3100 3975);
DISPLAY INVISIBLE (3100 3975);
FORCEADD OFFPAGE..3
R 2
(-1100 1625);
FORCEPROP 2 LAST $XR0 241 
J 0
(-1380 1625);
DISPLAY 0.638298 (-1380 1625);
PAINT MONO (-1380 1625);
FORCEPROP 1 LAST COMMENT_BODY TRUE
J 2
(-1050 1525);
DISPLAY 0.872340 (-1050 1525);
PAINT GREEN (-1050 1525);
DISPLAY INVISIBLE (-1050 1525);
FORCEPROP 1 LAST OFFPAGE TRUE
J 2
(-1425 1500);
DISPLAY 0.872340 (-1425 1500);
DISPLAY INVISIBLE (-1425 1500);
FORCEPROP 2 LAST CDS_LIB standard
J 0
(-1100 1625);
PAINT MONO (-1100 1625);
DISPLAY INVISIBLE (-1100 1625);
FORCEPROP 2 LAST PATH I5
J 0
(-1375 1675);
DISPLAY 1.021277 (-1375 1675);
DISPLAY INVISIBLE (-1375 1675);
FORCEADD OFFPAGE..1
(-1100 1725);
FORCEPROP 2 LAST $XR0 230 
J 0
(-1352 1725);
DISPLAY 0.638298 (-1352 1725);
PAINT MONO (-1352 1725);
FORCEPROP 1 LAST COMMENT_BODY TRUE
J 0
(-975 1625);
DISPLAY 0.872340 (-975 1625);
PAINT GREEN (-975 1625);
DISPLAY INVISIBLE (-975 1625);
FORCEPROP 1 LAST OFFPAGE TRUE
J 0
(-775 1600);
DISPLAY 0.872340 (-775 1600);
PAINT GREEN (-775 1600);
DISPLAY INVISIBLE (-775 1600);
FORCEPROP 2 LAST CDS_LIB standard
J 0
(-1100 1725);
PAINT MONO (-1100 1725);
DISPLAY INVISIBLE (-1100 1725);
FORCEPROP 2 LAST PATH I6
J 0
(-1350 1775);
DISPLAY 1.021277 (-1350 1775);
DISPLAY INVISIBLE (-1350 1775);
FORCEADD OFFPAGE..1
(-1100 1775);
FORCEPROP 2 LAST $XR0 241 
J 0
(-1352 1775);
DISPLAY 0.638298 (-1352 1775);
PAINT MONO (-1352 1775);
FORCEPROP 1 LAST COMMENT_BODY TRUE
J 0
(-975 1675);
DISPLAY 0.872340 (-975 1675);
PAINT GREEN (-975 1675);
DISPLAY INVISIBLE (-975 1675);
FORCEPROP 1 LAST OFFPAGE TRUE
J 0
(-775 1650);
DISPLAY 0.872340 (-775 1650);
PAINT GREEN (-775 1650);
DISPLAY INVISIBLE (-775 1650);
FORCEPROP 2 LAST CDS_LIB standard
J 0
(-1100 1775);
PAINT MONO (-1100 1775);
DISPLAY INVISIBLE (-1100 1775);
FORCEPROP 2 LAST PATH I7
J 0
(-1350 1825);
DISPLAY 1.021277 (-1350 1825);
DISPLAY INVISIBLE (-1350 1825);
FORCEADD OFFPAGE..3
R 2
(-1100 1875);
FORCEPROP 2 LAST $XR0 230 
J 0
(-1380 1875);
DISPLAY 0.638298 (-1380 1875);
PAINT MONO (-1380 1875);
FORCEPROP 1 LAST COMMENT_BODY TRUE
J 2
(-1050 1775);
DISPLAY 0.872340 (-1050 1775);
PAINT GREEN (-1050 1775);
DISPLAY INVISIBLE (-1050 1775);
FORCEPROP 1 LAST OFFPAGE TRUE
J 2
(-1425 1750);
DISPLAY 0.872340 (-1425 1750);
DISPLAY INVISIBLE (-1425 1750);
FORCEPROP 2 LAST CDS_LIB standard
J 0
(-1100 1875);
PAINT MONO (-1100 1875);
DISPLAY INVISIBLE (-1100 1875);
FORCEPROP 2 LAST PATH I8
J 0
(-1375 1925);
DISPLAY 1.021277 (-1375 1925);
DISPLAY INVISIBLE (-1375 1925);
FORCEADD OFFPAGE..3
R 2
(-1100 1925);
FORCEPROP 2 LAST $XR0 241 
J 0
(-1380 1925);
DISPLAY 0.638298 (-1380 1925);
PAINT MONO (-1380 1925);
FORCEPROP 1 LAST COMMENT_BODY TRUE
J 2
(-1050 1825);
DISPLAY 0.872340 (-1050 1825);
PAINT GREEN (-1050 1825);
DISPLAY INVISIBLE (-1050 1825);
FORCEPROP 1 LAST OFFPAGE TRUE
J 2
(-1425 1800);
DISPLAY 0.872340 (-1425 1800);
DISPLAY INVISIBLE (-1425 1800);
FORCEPROP 2 LAST CDS_LIB standard
J 0
(-1100 1925);
PAINT MONO (-1100 1925);
DISPLAY INVISIBLE (-1100 1925);
FORCEPROP 2 LAST PATH I9
J 0
(-1375 1975);
DISPLAY 1.021277 (-1375 1975);
DISPLAY INVISIBLE (-1375 1975);
FORCEADD DNS..2
(630 770);
PAINT RED (630 770);
FORCEPROP 1 LAST COMMENT_BODY TRUE
J 0
(630 770);
DISPLAY INVISIBLE (630 770);
FORCEPROP 2 LAST CDS_LIB mstr_misc
J 0
(630 770);
PAINT MONO (630 770);
DISPLAY INVISIBLE (630 770);
FORCEADD DNS..2
(630 895);
PAINT RED (630 895);
FORCEPROP 1 LAST COMMENT_BODY TRUE
J 0
(630 895);
DISPLAY INVISIBLE (630 895);
FORCEPROP 2 LAST CDS_LIB mstr_misc
J 0
(630 895);
PAINT MONO (630 895);
DISPLAY INVISIBLE (630 895);
FORCEADD DNS..2
(630 1020);
PAINT RED (630 1020);
FORCEPROP 1 LAST COMMENT_BODY TRUE
J 0
(630 1020);
DISPLAY INVISIBLE (630 1020);
FORCEPROP 2 LAST CDS_LIB mstr_misc
J 0
(630 1020);
PAINT MONO (630 1020);
DISPLAY INVISIBLE (630 1020);
FORCEADD DNS..2
(630 1145);
PAINT RED (630 1145);
FORCEPROP 1 LAST COMMENT_BODY TRUE
J 0
(630 1145);
DISPLAY INVISIBLE (630 1145);
FORCEPROP 2 LAST CDS_LIB mstr_misc
J 0
(630 1145);
PAINT MONO (630 1145);
DISPLAY INVISIBLE (630 1145);
FORCEADD QUANTA_TITLE_BLOCK_C..1
(5750 -1150);
FORCEPROP 0 LAST CDS_CON_LAST_MODIFIED Fri Aug 25 14:03:53 2023
J 0
(3865 -1135);
PAINT MONO (3865 -1135);
DISPLAY INVISIBLE (3865 -1135);
FORCEPROP 2 LAST CUSTOM_TXT_CDS <XR_PAGE_TITLE>
J 0
(-2140 4100);
DISPLAY 0.638298 (-2140 4100);
PAINT PINK (-2140 4100);
DISPLAY INVISIBLE (-2140 4100);
FORCEPROP 2 LAST CUSTOM_TXT_CDS <CON_LAST_MODIFIED>
J 0
(3865 -1135);
DISPLAY 0.978723 (3865 -1135);
FORCEPROP 2 LAST CUSTOM_TXT_CDS <NAME_2>
J 0
(2575 -1100);
FORCEPROP 2 LAST CUSTOM_TXT_CDS <NAME_1>
J 0
(2575 -975);
FORCEPROP 2 LAST CUSTOM_TXT_CDS <Q_NUMBER>
J 0
(4347 -1047);
DISPLAY 1.212766 (4347 -1047);
FORCEPROP 2 LAST CUSTOM_TXT_CDS <Q_PROJ>
J 0
(3368 -1048);
DISPLAY 1.212766 (3368 -1048);
FORCEPROP 2 LAST CUSTOM_TXT_CDS <Q_REV>
J 0
(5566 -1047);
DISPLAY 1.212766 (5566 -1047);
FORCEPROP 2 LAST CUSTOM_TXT_CDS <CON_PAGE_NUM> OF <CON_TOTAL_PAGES>
J 0
(5304 -1132);
DISPLAY 0.978723 (5304 -1132);
FORCEPROP 1 LAST Q_TITLE SMBUS - I3C CPU1 SPD
J 0
(-3516 -1149);
DISPLAY 2.446809 (-3516 -1149);
PAINT GREEN (-3516 -1149);
FORCEPROP 1 LAST Q_DEPT 
J 1
(1987 -1101);
DISPLAY 1.957447 (1987 -1101);
PAINT GREEN (1987 -1101);
FORCEPROP 2 LAST PAGE_BORDER TRUE
J 0
(-2140 4100);
DISPLAY 0.638298 (-2140 4100);
PAINT PINK (-2140 4100);
DISPLAY INVISIBLE (-2140 4100);
FORCEPROP 1 LAST COMMENT_BODY TRUE
J 0
(5762 -1163);
DISPLAY 0.978723 (5762 -1163);
PAINT GREEN (5762 -1163);
DISPLAY INVISIBLE (5762 -1163);
FORCEPROP 1 LAST CDS_LMAN_SYM_OUTLINE -9475,6775,100,-125
J 0
(5750 -1150);
DISPLAY 0.468085 (5750 -1150);
PAINT GREEN (5750 -1150);
DISPLAY INVISIBLE (5750 -1150);
FORCEPROP 2 LAST CDS_LIB pure_quanta
J 0
(5750 -1150);
PAINT MONO (5750 -1150);
DISPLAY INVISIBLE (5750 -1150);
FORCEPROP 2 LAST CDS_XR_PAGE_TITLE CR-230 : @S9S_MB_2U_LIB.S9S_MB_2U(SCH_1):PAGE230
J 0
(-2140 4100);
DISPLAY 0.638298 (-2140 4100);
PAINT PINK (-2140 4100);
DISPLAY INVISIBLE (-2140 4100);
WIRE 16 -1 (-25 4625)(-25 4525);
WIRE 16 -1 (1025 2625)(1025 2550);
WIRE 16 -1 (-1050 1050)(-1050 1125);
WIRE 16 -1 (1025 1350)(1025 1425);
WIRE 16 -1 (1250 2150)(1250 2250);
WIRE 16 -1 (4050 2025)(2850 2025);
FORCEPROP 2 LAST SIG_NAME I3C_SPD_DDRABCD_CPU1_LVC1_SCL
J 0
(3065 2035);
DISPLAY 0.680851 (3065 2035);
PAINT WHITE (3065 2035);
WIRE 16 -1 (4050 1875)(2850 1875);
FORCEPROP 2 LAST SIG_NAME I3C_SPD_DDRABCD_CPU1_LVC1_SDA
J 0
(3065 1885);
DISPLAY 0.680851 (3065 1885);
PAINT WHITE (3065 1885);
WIRE 16 -1 (4050 1725)(2850 1725);
FORCEPROP 2 LAST SIG_NAME I3C_SPD_DDREFGH_CPU1_LVC1_SCL
J 0
(3065 1735);
DISPLAY 0.680851 (3065 1735);
PAINT WHITE (3065 1735);
WIRE 16 -1 (4050 1575)(2850 1575);
FORCEPROP 2 LAST SIG_NAME I3C_SPD_DDREFGH_CPU1_LVC1_SDA
J 0
(3065 1585);
DISPLAY 0.680851 (3065 1585);
PAINT WHITE (3065 1585);
WIRE 16 2175 (2525 1825)(3025 1825);
WIRE 16 2175 (3025 1950)(3025 1825);
WIRE 16 2175 (2525 1950)(2525 1825);
WIRE 16 2175 (2525 1950)(3025 1950);
WIRE 16 2175 (2525 1550)(3025 1550);
WIRE 16 2175 (3025 1675)(3025 1550);
WIRE 16 2175 (2525 1675)(2525 1550);
WIRE 16 2175 (2525 1675)(3025 1675);
WIRE 16 -1 (1225 3975)(2825 3975);
FORCEPROP 2 LAST SIG_NAME I3C_SPD_DDRABCD_CPU1_R_SCL
J 0
(1790 3985);
DISPLAY 0.680851 (1790 3985);
PAINT WHITE (1790 3985);
WIRE 16 -1 (2825 3925)(1225 3925);
FORCEPROP 2 LAST SIG_NAME I3C_SPD_DDRABCD_CPU1_R_SDA
J 0
(1790 3935);
DISPLAY 0.680851 (1790 3935);
PAINT WHITE (1790 3935);
WIRE 16 -1 (1225 3675)(2825 3675);
FORCEPROP 2 LAST SIG_NAME I3C_SPD_DDREFGH_CPU1_R_SCL
J 0
(1790 3685);
DISPLAY 0.680851 (1790 3685);
PAINT WHITE (1790 3685);
WIRE 16 -1 (2825 3625)(1225 3625);
FORCEPROP 2 LAST SIG_NAME I3C_SPD_DDREFGH_CPU1_R_SDA
J 0
(1790 3635);
DISPLAY 0.680851 (1790 3635);
PAINT WHITE (1790 3635);
WIRE 16 -1 (-25 4525)(-25 4400);
WIRE 16 -1 (225 4525)(-25 4525);
WIRE 16 -1 (225 4400)(225 4525);
WIRE 16 -1 (475 4525)(225 4525);
WIRE 16 -1 (475 4400)(475 4525);
WIRE 16 -1 (725 4525)(725 4400);
WIRE 16 -1 (725 4525)(475 4525);
WIRE 16 -1 (1025 2075)(950 2075);
WIRE 16 -1 (1025 2550)(1025 2075);
WIRE 16 -1 (1250 2450)(1250 2550);
WIRE 16 -1 (1250 2550)(1025 2550);
WIRE 16 -1 (1100 1150)(725 1150);
WIRE 16 -1 (1100 2025)(950 2025);
WIRE 16 -1 (1100 2025)(1100 1150);
WIRE 16 -1 (2650 2025)(1100 2025);
FORCEPROP 2 LAST SIG_NAME I3C_SPD_DDRABCD_CPU1_LVC1_R_SCL
J 0
(1415 2035);
DISPLAY 0.680851 (1415 2035);
PAINT WHITE (1415 2035);
WIRE 16 -1 (1175 1025)(725 1025);
WIRE 16 -1 (1175 1875)(950 1875);
WIRE 16 -1 (1175 1875)(1175 1025);
WIRE 16 -1 (2650 1875)(1175 1875);
FORCEPROP 2 LAST SIG_NAME I3C_SPD_DDRABCD_CPU1_LVC1_R_SDA
J 0
(1415 1885);
DISPLAY 0.680851 (1415 1885);
PAINT WHITE (1415 1885);
WIRE 16 -1 (1250 900)(725 900);
WIRE 16 -1 (1250 1725)(950 1725);
WIRE 16 -1 (1250 1725)(1250 900);
WIRE 16 -1 (2650 1725)(1250 1725);
FORCEPROP 2 LAST SIG_NAME I3C_SPD_DDREFGH_CPU1_LVC1_R_SCL
J 0
(1415 1735);
DISPLAY 0.680851 (1415 1735);
PAINT WHITE (1415 1735);
WIRE 16 -1 (1325 775)(725 775);
WIRE 16 -1 (1325 1575)(950 1575);
WIRE 16 -1 (1325 1575)(1325 775);
WIRE 16 -1 (2650 1575)(1325 1575);
FORCEPROP 2 LAST SIG_NAME I3C_SPD_DDREFGH_CPU1_LVC1_R_SDA
J 0
(1415 1585);
DISPLAY 0.680851 (1415 1585);
PAINT WHITE (1415 1585);
WIRE 16 -1 (950 1425)(1025 1425);
WIRE 16 -1 (725 3625)(-1050 3625);
FORCEPROP 2 LAST SIG_NAME I3C_SPD_DDREFGH_CPU1_SDA
J 0
(-935 3635);
DISPLAY 0.680851 (-935 3635);
PAINT WHITE (-935 3635);
WIRE 16 -1 (1025 3625)(725 3625);
WIRE 16 -1 (725 4200)(725 3625);
WIRE 16 -1 (475 3675)(-1050 3675);
FORCEPROP 2 LAST SIG_NAME I3C_SPD_DDREFGH_CPU1_SCL
J 0
(-935 3685);
DISPLAY 0.680851 (-935 3685);
PAINT WHITE (-935 3685);
WIRE 16 -1 (1025 3675)(475 3675);
WIRE 16 -1 (475 4200)(475 3675);
WIRE 16 -1 (-25 3975)(-1050 3975);
FORCEPROP 2 LAST SIG_NAME I3C_SPD_DDRABCD_CPU1_SCL
J 0
(-935 3985);
DISPLAY 0.680851 (-935 3985);
PAINT WHITE (-935 3985);
WIRE 16 -1 (-25 4200)(-25 3975);
WIRE 16 -1 (1025 3975)(-25 3975);
WIRE 16 -1 (225 3925)(-1050 3925);
FORCEPROP 2 LAST SIG_NAME I3C_SPD_DDRABCD_CPU1_SDA
J 0
(-935 3935);
DISPLAY 0.680851 (-935 3935);
PAINT WHITE (-935 3935);
WIRE 16 -1 (1025 3925)(225 3925);
WIRE 16 -1 (225 4200)(225 3925);
WIRE 16 -1 (525 775)(0 775);
WIRE 16 -1 (0 1575)(0 775);
WIRE 16 -1 (0 1575)(-1050 1575);
FORCEPROP 2 LAST SIG_NAME I3C_SPD_DDREFGH_CPU1_R_SDA
J 0
(-935 1585);
DISPLAY 0.680851 (-935 1585);
PAINT WHITE (-935 1585);
WIRE 16 -1 (350 1575)(0 1575);
WIRE 16 -1 (525 900)(75 900);
WIRE 16 -1 (75 1725)(-1050 1725);
FORCEPROP 2 LAST SIG_NAME I3C_SPD_DDREFGH_CPU1_R_SCL
J 0
(-935 1735);
DISPLAY 0.680851 (-935 1735);
PAINT WHITE (-935 1735);
WIRE 16 -1 (75 1725)(75 900);
WIRE 16 -1 (350 1725)(75 1725);
WIRE 16 -1 (225 1150)(525 1150);
WIRE 16 -1 (225 2025)(-1050 2025);
FORCEPROP 2 LAST SIG_NAME I3C_SPD_DDRABCD_CPU1_R_SCL
J 0
(-935 2035);
DISPLAY 0.680851 (-935 2035);
PAINT WHITE (-935 2035);
WIRE 16 -1 (225 2025)(225 1150);
WIRE 16 -1 (350 2025)(225 2025);
WIRE 16 -1 (525 1025)(150 1025);
WIRE 16 -1 (150 1875)(-1050 1875);
FORCEPROP 2 LAST SIG_NAME I3C_SPD_DDRABCD_CPU1_R_SDA
J 0
(-935 1885);
DISPLAY 0.680851 (-935 1885);
PAINT WHITE (-935 1885);
WIRE 16 -1 (150 1875)(150 1025);
WIRE 16 -1 (350 1875)(150 1875);
WIRE 16 -1 (350 1925)(-1050 1925);
FORCEPROP 2 LAST SIG_NAME I3C_SPD_DDRABCD_CPU1_BMC_SDA
J 0
(-935 1935);
DISPLAY 0.680851 (-935 1935);
PAINT WHITE (-935 1935);
WIRE 16 -1 (350 1625)(-1050 1625);
FORCEPROP 2 LAST SIG_NAME I3C_SPD_DDREFGH_CPU1_BMC_SDA
J 0
(-935 1635);
DISPLAY 0.680851 (-935 1635);
PAINT WHITE (-935 1635);
WIRE 16 -1 (350 2075)(-1050 2075);
FORCEPROP 2 LAST SIG_NAME I3C_SPD_DDRABCD_CPU1_BMC_SCL
J 0
(-935 2085);
DISPLAY 0.680851 (-935 2085);
PAINT WHITE (-935 2085);
WIRE 16 -1 (350 1475)(-1050 1475);
FORCEPROP 2 LAST SIG_NAME FM_SPD_REMOTE_EN
J 0
(-935 1485);
DISPLAY 0.680851 (-935 1485);
PAINT WHITE (-935 1485);
WIRE 16 -1 (350 1775)(-1050 1775);
FORCEPROP 2 LAST SIG_NAME I3C_SPD_DDREFGH_CPU1_BMC_SCL
J 0
(-935 1785);
DISPLAY 0.680851 (-935 1785);
PAINT WHITE (-935 1785);
WIRE 16 -1 (350 1425)(-1050 1425);
FORCEPROP 2 LAST SIG_NAME PD_I3C_SPD_DDR_CPU1_OE_N
J 0
(-935 1435);
DISPLAY 0.680851 (-935 1435);
PAINT WHITE (-935 1435);
WIRE 16 -1 (-1050 1325)(-1050 1425);
DOT 1 (0 1575);
DOT 1 (75 1725);
DOT 1 (150 1875);
DOT 1 (225 2025);
DOT 1 (225 3925);
DOT 1 (-25 3975);
DOT 1 (-25 4525);
DOT 1 (225 4525);
DOT 1 (1175 1875);
DOT 1 (1100 2025);
DOT 1 (1325 1575);
DOT 1 (1250 1725);
DOT 1 (1025 2550);
DOT 1 (725 3625);
DOT 1 (475 3675);
DOT 1 (475 4525);
FORCENOTE
20221221 CHANGE R675,R677 TO 33.2 OHM
(2125 1425) 0;
DISPLAY LEFT (2125 1425);
DISPLAY 1.063830 (2125 1425);
PAINT WHITE (2125 1425);
QUIT
